(kicad_pcb
	(version 20260206)
	(generator "pcbnew")
	(generator_version "10.0")
	(general
		(thickness 1.6)
		(legacy_teardrops no)
	)
	(paper "A4")
	(title_block
		(title "Wiwynn_Tioga_Pass_MB.brd")
		(comment 1 "Tioga Pass / footprints 50-56 of 4770")
	)
	(layers
		(0 "F.Cu" signal "TOP")
		(4 "In1.Cu" signal "L2GND")
		(6 "In2.Cu" signal "L3")
		(8 "In3.Cu" signal "L4GND")
		(10 "In4.Cu" signal "L5")
		(12 "In5.Cu" signal "L6GND")
		(14 "In6.Cu" signal "L7VCC")
		(16 "In7.Cu" signal "L8VCC")
		(18 "In8.Cu" signal "L9GND")
		(20 "In9.Cu" signal "L10")
		(22 "In10.Cu" signal "L11GND")
		(24 "In11.Cu" signal "L12")
		(26 "In12.Cu" signal "L13GND")
		(2 "B.Cu" signal "BOTTOM")
		(9 "F.Adhes" user "F.Adhesive")
		(11 "B.Adhes" user "B.Adhesive")
		(13 "F.Paste" user "Package Geometry/Pastemask Top")
		(15 "B.Paste" user "Package Geometry/Pastemask Bottom")
		(5 "F.SilkS" user "Ref Des/Silkscreen Top")
		(7 "B.SilkS" user "Ref Des/Silkscreen Bottom")
		(1 "F.Mask" user "Board Geometry/Soldermask Top")
		(3 "B.Mask" user "Board Geometry/Soldermask Bottom")
		(17 "Dwgs.User" user "User.Drawings")
		(19 "Cmts.User" user "User.Comments")
		(21 "Eco1.User" user "User.Eco1")
		(23 "Eco2.User" user "User.Eco2")
		(25 "Edge.Cuts" user "Board Geometry/Outline")
		(27 "Margin" user)
		(31 "F.CrtYd" user "Package Geometry/Place Bound Top")
		(29 "B.CrtYd" user "Package Geometry/Place Bound Bottom")
		(35 "F.Fab" user "Ref Des/Assembly Top")
		(33 "B.Fab" user "Ref Des/Assembly Bottom")
	)
	(footprint ""
		(layer "F.Cu")
		(at 439.976006 -43.568874 180)
		(property "Reference" "R25W33"
			(at 0 0 180)
			(layer "F.SilkS")
			(hide yes)
			(effects
				(font
					(size 1.27 1.27)
				)
			)
		)
		(property "Value" "*"
			(at 0.064008 -4.108196 180)
			(unlocked yes)
			(layer "F.Fab")
			(hide yes)
			(effects
				(font
					(size 1.27 1.016)
					(thickness 0.1524)
				)
			)
		)
		(property "Device Type" "120R2F-GP_RCL_GP-120R2F-GP,64.A"
			(at 0.064008 -5.632196 180)
			(unlocked yes)
			(layer "F.Fab")
			(hide yes)
			(effects
				(font
					(size 1.27 1.016)
					(thickness 0.1524)
				)
			)
		)
		(duplicate_pad_numbers_are_jumpers no)
		(fp_line
			(start 0.508 -0.9398)
			(end -0.508 -0.9398)
			(stroke
				(width 0.1524)
				(type default)
			)
			(layer "F.SilkS")
		)
		(fp_line
			(start -0.508 -0.9398)
			(end -0.508 0.9398)
			(stroke
				(width 0.1524)
				(type default)
			)
			(layer "F.SilkS")
		)
		(fp_rect
			(start -0.508 0.9398)
			(end 0.508 -0.9398)
			(stroke
				(width 0)
				(type default)
			)
			(fill no)
			(layer "F.CrtYd")
		)
		(fp_rect
			(start -0.508 0.9398)
			(end 0.508 -0.9398)
			(stroke
				(width 0)
				(type default)
			)
			(fill no)
			(layer "F.Fab")
		)
		(pad "1" smd custom
			(at 0 -0.4445 180)
			(size 0.1397 0.1397)
			(layers "F.Cu" "F.Mask" "F.Paste")
			(net "BMC_M_CAS_N")
			(options
				(clearance outline)
				(anchor circle)
			)
			(primitives
				(gr_poly
					(pts
						(arc
							(start -0.1778 -0.2794)
							(mid -0.249642 -0.249642)
							(end -0.2794 -0.1778)
						)
						(arc
							(start -0.2794 0.1778)
							(mid -0.249642 0.249642)
							(end -0.1778 0.2794)
						)
						(arc
							(start 0.1778 0.2794)
							(mid 0.249642 0.249642)
							(end 0.2794 0.1778)
						)
						(arc
							(start 0.2794 -0.1778)
							(mid 0.249642 -0.249642)
							(end 0.1778 -0.2794)
						)
					)
					(width 0)
					(fill yes)
				)
			)
		)
		(pad "2" smd custom
			(at 0 0.4445 180)
			(size 0.1397 0.1397)
			(layers "F.Cu" "F.Mask" "F.Paste")
			(net "P1V2_AUX_BMC")
			(options
				(clearance outline)
				(anchor circle)
			)
			(primitives
				(gr_poly
					(pts
						(arc
							(start -0.1778 -0.2794)
							(mid -0.249642 -0.249642)
							(end -0.2794 -0.1778)
						)
						(arc
							(start -0.2794 0.1778)
							(mid -0.249642 0.249642)
							(end -0.1778 0.2794)
						)
						(arc
							(start 0.1778 0.2794)
							(mid 0.249642 0.249642)
							(end 0.2794 0.1778)
						)
						(arc
							(start 0.2794 -0.1778)
							(mid 0.249642 -0.249642)
							(end 0.1778 -0.2794)
						)
					)
					(width 0)
					(fill yes)
				)
			)
		)
	)
	(footprint ""
		(layer "F.Cu")
		(at 163.576 -80.518 -90)
		(property "Reference" "R4D19"
			(at 0 0 270)
			(layer "F.SilkS")
			(hide yes)
			(effects
				(font
					(size 1.27 1.27)
				)
			)
		)
		(property "Value" ""
			(at 0 0 270)
			(layer "F.Fab")
			(effects
				(font
					(size 1.27 1.27)
				)
			)
		)
		(duplicate_pad_numbers_are_jumpers no)
		(fp_poly
			(pts
				(xy -0.2794 -0.1016) (xy 0.2794 -0.1016) (xy 0.2794 0.9906) (xy -0.2794 0.9906)
			)
			(stroke
				(width 0)
				(type default)
			)
			(fill no)
			(layer "F.CrtYd")
		)
		(fp_line
			(start -0.2794 0.9906)
			(end 0.2794 0.9906)
			(stroke
				(width 0.1)
				(type default)
			)
			(layer "F.Fab")
		)
		(fp_line
			(start 0.2794 0.9906)
			(end 0.2794 -0.1016)
			(stroke
				(width 0.1)
				(type default)
			)
			(layer "F.Fab")
		)
		(fp_line
			(start -0.2794 -0.1016)
			(end -0.2794 0.9906)
			(stroke
				(width 0.1)
				(type default)
			)
			(layer "F.Fab")
		)
		(fp_line
			(start 0.2794 -0.1016)
			(end -0.2794 -0.1016)
			(stroke
				(width 0.1)
				(type default)
			)
			(layer "F.Fab")
		)
		(pad "1" smd rect
			(at 0 0 270)
			(size 0.508 0.508)
			(layers "F.Cu" "F.Mask" "F.Paste")
			(net "CLK_100M_CPU1_RC_REFCLK0_R_DP")
		)
		(pad "2" smd rect
			(at 0 0.889 270)
			(size 0.508 0.508)
			(layers "F.Cu" "F.Mask" "F.Paste")
			(net "CLK_100M_CPU1_RC_REFCLK0_DP")
		)
		(zone
			(layer "F.Cu")
			(hatch none 0.5)
			(connect_pads
				(clearance 0)
			)
			(min_thickness 0.25)
			(keepout
				(tracks not_allowed)
				(vias allowed)
				(pads allowed)
				(copperpour not_allowed)
				(footprints allowed)
			)
			(placement
				(enabled no)
				(sheetname "")
			)
			(fill
				(thermal_gap 0.5)
				(thermal_bridge_width 0.5)
				(island_removal_mode 0)
			)
			(polygon
				(pts
					(xy 162.941 -80.772) (xy 162.941 -80.264) (xy 163.322 -80.264) (xy 163.322 -80.772)
				)
			)
		)
		(zone
			(layer "F.Cu")
			(hatch none 0.5)
			(connect_pads
				(clearance 0)
			)
			(min_thickness 0.25)
			(keepout
				(tracks allowed)
				(vias not_allowed)
				(pads allowed)
				(copperpour not_allowed)
				(footprints allowed)
			)
			(placement
				(enabled no)
				(sheetname "")
			)
			(fill
				(thermal_gap 0.5)
				(thermal_bridge_width 0.5)
				(island_removal_mode 0)
			)
			(polygon
				(pts
					(xy 163.322 -80.772) (xy 163.322 -80.264) (xy 162.941 -80.264) (xy 162.941 -80.772)
				)
			)
		)
	)
	(footprint ""
		(layer "F.Cu")
		(at 171.8818 -3.175 180)
		(property "Reference" "EU4G2"
			(at 2.9718 -1.42367 0)
			(unlocked yes)
			(layer "F.SilkS")
			(effects
				(font
					(size 0.7874 0.5842)
					(thickness 0.1524)
				)
				(justify left)
			)
		)
		(property "Value" ""
			(at 0 0 180)
			(layer "F.Fab")
			(effects
				(font
					(size 1.27 1.27)
				)
			)
		)
		(duplicate_pad_numbers_are_jumpers no)
		(fp_circle
			(center -0.835152 -0.417322)
			(end -0.962152 -0.417322)
			(stroke
				(width 0.254)
				(type default)
			)
			(fill no)
			(layer "F.SilkS")
		)
		(fp_poly
			(pts
				(xy -0.064516 -1.0922) (xy -0.064516 -0.3302) (xy 0.697484 -1.0922)
			)
			(stroke
				(width 0)
				(type default)
			)
			(fill yes)
			(layer "F.SilkS")
		)
		(fp_rect
			(start 0.597408 2.295398)
			(end 2.273808 -0.295402)
			(stroke
				(width 0)
				(type default)
			)
			(fill yes)
			(layer "F.Paste")
		)
		(fp_rect
			(start -0.064516 2.500122)
			(end 2.935478 -0.500126)
			(stroke
				(width 0)
				(type default)
			)
			(fill no)
			(layer "F.CrtYd")
		)
		(fp_line
			(start 2.935478 2.500122)
			(end -0.064516 2.500122)
			(stroke
				(width 0.1)
				(type default)
			)
			(layer "F.Fab")
		)
		(fp_line
			(start 2.935478 -0.500126)
			(end 2.935478 2.500122)
			(stroke
				(width 0.1)
				(type default)
			)
			(layer "F.Fab")
		)
		(fp_line
			(start -0.064516 2.500122)
			(end -0.064516 -0.500126)
			(stroke
				(width 0.1)
				(type default)
			)
			(layer "F.Fab")
		)
		(fp_line
			(start -0.064516 -0.500126)
			(end 2.935478 -0.500126)
			(stroke
				(width 0.1)
				(type default)
			)
			(layer "F.Fab")
		)
		(fp_circle
			(center -0.835152 -0.417322)
			(end -0.962152 -0.417322)
			(stroke
				(width 0.254)
				(type default)
			)
			(fill no)
			(layer "F.Fab")
		)
		(pad "1" smd rect
			(at 0 0 180)
			(size 0.6858 0.3048)
			(layers "F.Cu" "F.Mask" "F.Paste")
			(net "VR_PVTT_GHJ_VREF")
		)
		(pad "2" smd rect
			(at 0 0.500126 180)
			(size 0.6858 0.3048)
			(layers "F.Cu" "F.Mask" "F.Paste")
			(net "VR_PVTT_GHJ_BIAS")
		)
		(pad "3" smd rect
			(at 0 0.999998 180)
			(size 0.6858 0.3048)
			(layers "F.Cu" "F.Mask" "F.Paste")
			(net "GND")
		)
		(pad "4" smd rect
			(at 0 1.500124 180)
			(size 0.6858 0.3048)
			(layers "F.Cu" "F.Mask" "F.Paste")
			(net "VSENSE_PVDDQ_GHJ_VTT")
		)
		(pad "5" smd rect
			(at 0 1.999996 180)
			(size 0.6858 0.3048)
			(layers "F.Cu" "F.Mask" "F.Paste")
			(net "PWRGD_PVTT_GHJ_CPU1_R")
		)
		(pad "6" smd rect
			(at 2.871216 1.999996 180)
			(size 0.6858 0.3048)
			(layers "F.Cu" "F.Mask" "F.Paste")
			(net "VR_PVTT_GHJ_SNS")
		)
		(pad "7" smd rect
			(at 2.871216 1.500124 180)
			(size 0.6858 0.3048)
			(layers "F.Cu" "F.Mask" "F.Paste")
			(net "FM_PVTT_GHJ_EN_R")
		)
		(pad "8" smd rect
			(at 2.871216 0.999998 180)
			(size 0.6858 0.3048)
			(layers "F.Cu" "F.Mask" "F.Paste")
			(net "GND")
		)
		(pad "9" smd rect
			(at 2.871216 0.500126 180)
			(size 0.6858 0.3048)
			(layers "F.Cu" "F.Mask" "F.Paste")
			(net "PVTT_GHJ")
		)
		(pad "10" smd rect
			(at 2.871216 0 180)
			(size 0.6858 0.3048)
			(layers "F.Cu" "F.Mask" "F.Paste")
			(net "PVDDQ_GHJ")
		)
		(pad "11" smd rect
			(at 1.435608 0.999998 180)
			(size 1.6764 2.5908)
			(layers "F.Cu" "F.Mask" "F.Paste")
			(net "GND")
		)
	)
	(footprint ""
		(layer "F.Cu")
		(at 401.55368 -28.49499 180)
		(property "Reference" "R25W148"
			(at -0.8382 -0.67818 180)
			(unlocked yes)
			(layer "F.SilkS")
			(effects
				(font
					(size 0.4064 0.254)
					(thickness 0.1524)
				)
				(justify left)
			)
		)
		(property "Value" ""
			(at 0 0 180)
			(layer "F.Fab")
			(effects
				(font
					(size 1.27 1.27)
				)
			)
		)
		(duplicate_pad_numbers_are_jumpers no)
		(fp_poly
			(pts
				(xy -0.2794 -0.1016) (xy 0.2794 -0.1016) (xy 0.2794 0.9906) (xy -0.2794 0.9906)
			)
			(stroke
				(width 0)
				(type default)
			)
			(fill no)
			(layer "F.CrtYd")
		)
		(fp_line
			(start 0.2794 0.9906)
			(end 0.2794 -0.1016)
			(stroke
				(width 0.1)
				(type default)
			)
			(layer "F.Fab")
		)
		(fp_line
			(start 0.2794 -0.1016)
			(end -0.2794 -0.1016)
			(stroke
				(width 0.1)
				(type default)
			)
			(layer "F.Fab")
		)
		(fp_line
			(start -0.2794 0.9906)
			(end 0.2794 0.9906)
			(stroke
				(width 0.1)
				(type default)
			)
			(layer "F.Fab")
		)
		(fp_line
			(start -0.2794 -0.1016)
			(end -0.2794 0.9906)
			(stroke
				(width 0.1)
				(type default)
			)
			(layer "F.Fab")
		)
		(pad "1" smd rect
			(at 0 0 180)
			(size 0.508 0.508)
			(layers "F.Cu" "F.Mask" "F.Paste")
			(net "GND")
		)
		(pad "2" smd rect
			(at 0 0.889 180)
			(size 0.508 0.508)
			(layers "F.Cu" "F.Mask" "F.Paste")
			(net "RMII_BMC_OCP_TXD1_R")
		)
		(zone
			(layer "F.Cu")
			(hatch none 0.5)
			(connect_pads
				(clearance 0)
			)
			(min_thickness 0.25)
			(keepout
				(tracks not_allowed)
				(vias allowed)
				(pads allowed)
				(copperpour not_allowed)
				(footprints allowed)
			)
			(placement
				(enabled no)
				(sheetname "")
			)
			(fill
				(thermal_gap 0.5)
				(thermal_bridge_width 0.5)
				(island_removal_mode 0)
			)
			(polygon
				(pts
					(xy 401.80768 -29.12999) (xy 401.29968 -29.12999) (xy 401.29968 -28.74899) (xy 401.80768 -28.74899)
				)
			)
		)
		(zone
			(layer "F.Cu")
			(hatch none 0.5)
			(connect_pads
				(clearance 0)
			)
			(min_thickness 0.25)
			(keepout
				(tracks allowed)
				(vias not_allowed)
				(pads allowed)
				(copperpour not_allowed)
				(footprints allowed)
			)
			(placement
				(enabled no)
				(sheetname "")
			)
			(fill
				(thermal_gap 0.5)
				(thermal_bridge_width 0.5)
				(island_removal_mode 0)
			)
			(polygon
				(pts
					(xy 401.80768 -28.74899) (xy 401.29968 -28.74899) (xy 401.29968 -29.12999) (xy 401.80768 -29.12999)
				)
			)
		)
	)
	(footprint ""
		(layer "F.Cu")
		(at 259.452872 -81.573116)
		(property "Reference" "C5D11"
			(at 0 0 0)
			(layer "F.SilkS")
			(hide yes)
			(effects
				(font
					(size 1.27 1.27)
				)
			)
		)
		(property "Value" ""
			(at 0 0 0)
			(layer "F.Fab")
			(effects
				(font
					(size 1.27 1.27)
				)
			)
		)
		(duplicate_pad_numbers_are_jumpers no)
		(fp_poly
			(pts
				(xy -0.4953 -0.2032) (xy 0.4953 -0.2032) (xy 0.4953 1.6002) (xy -0.4953 1.6002)
			)
			(stroke
				(width 0)
				(type default)
			)
			(fill no)
			(layer "F.CrtYd")
		)
		(fp_line
			(start -0.4953 -0.2032)
			(end 0.4953 -0.2032)
			(stroke
				(width 0.1)
				(type default)
			)
			(layer "F.Fab")
		)
		(fp_line
			(start -0.4953 1.6002)
			(end -0.4953 -0.2032)
			(stroke
				(width 0.1)
				(type default)
			)
			(layer "F.Fab")
		)
		(fp_line
			(start 0.4953 -0.2032)
			(end 0.4953 1.6002)
			(stroke
				(width 0.1)
				(type default)
			)
			(layer "F.Fab")
		)
		(fp_line
			(start 0.4953 1.6002)
			(end -0.4953 1.6002)
			(stroke
				(width 0.1)
				(type default)
			)
			(layer "F.Fab")
		)
		(pad "1" smd rect
			(at 0 0)
			(size 0.762 0.889)
			(layers "F.Cu" "F.Mask" "F.Paste")
			(net "PVSA_CPU0")
		)
		(pad "2" smd rect
			(at 0 1.397)
			(size 0.762 0.889)
			(layers "F.Cu" "F.Mask" "F.Paste")
			(net "GND")
		)
		(zone
			(layer "F.Cu")
			(hatch none 0.5)
			(connect_pads
				(clearance 0)
			)
			(min_thickness 0.25)
			(keepout
				(tracks not_allowed)
				(vias allowed)
				(pads allowed)
				(copperpour not_allowed)
				(footprints allowed)
			)
			(placement
				(enabled no)
				(sheetname "")
			)
			(fill
				(thermal_gap 0.5)
				(thermal_bridge_width 0.5)
				(island_removal_mode 0)
			)
			(polygon
				(pts
					(xy 259.071872 -81.128616) (xy 259.833872 -81.128616) (xy 259.833872 -80.620616) (xy 259.071872 -80.620616)
				)
			)
		)
	)
	(footprint ""
		(layer "F.Cu")
		(at 171.6532 -8.6868 90)
		(property "Reference" "R4G4"
			(at 0 0 90)
			(layer "F.SilkS")
			(hide yes)
			(effects
				(font
					(size 1.27 1.27)
				)
			)
		)
		(property "Value" ""
			(at 0 0 90)
			(layer "F.Fab")
			(effects
				(font
					(size 1.27 1.27)
				)
			)
		)
		(duplicate_pad_numbers_are_jumpers no)
		(fp_poly
			(pts
				(xy -0.2794 -0.1016) (xy 0.2794 -0.1016) (xy 0.2794 0.9906) (xy -0.2794 0.9906)
			)
			(stroke
				(width 0)
				(type default)
			)
			(fill no)
			(layer "F.CrtYd")
		)
		(fp_line
			(start 0.2794 -0.1016)
			(end -0.2794 -0.1016)
			(stroke
				(width 0.1)
				(type default)
			)
			(layer "F.Fab")
		)
		(fp_line
			(start -0.2794 -0.1016)
			(end -0.2794 0.9906)
			(stroke
				(width 0.1)
				(type default)
			)
			(layer "F.Fab")
		)
		(fp_line
			(start 0.2794 0.9906)
			(end 0.2794 -0.1016)
			(stroke
				(width 0.1)
				(type default)
			)
			(layer "F.Fab")
		)
		(fp_line
			(start -0.2794 0.9906)
			(end 0.2794 0.9906)
			(stroke
				(width 0.1)
				(type default)
			)
			(layer "F.Fab")
		)
		(pad "1" smd rect
			(at 0 0 90)
			(size 0.508 0.508)
			(layers "F.Cu" "F.Mask" "F.Paste")
			(net "FM_PVPP_CPU1_EN")
		)
		(pad "2" smd rect
			(at 0 0.889 90)
			(size 0.508 0.508)
			(layers "F.Cu" "F.Mask" "F.Paste")
			(net "FM_PVPP_PVDDQ_CPU1_EN_GHJ")
		)
		(zone
			(layer "F.Cu")
			(hatch none 0.5)
			(connect_pads
				(clearance 0)
			)
			(min_thickness 0.25)
			(keepout
				(tracks allowed)
				(vias not_allowed)
				(pads allowed)
				(copperpour not_allowed)
				(footprints allowed)
			)
			(placement
				(enabled no)
				(sheetname "")
			)
			(fill
				(thermal_gap 0.5)
				(thermal_bridge_width 0.5)
				(island_removal_mode 0)
			)
			(polygon
				(pts
					(xy 171.9072 -8.4328) (xy 171.9072 -8.9408) (xy 172.2882 -8.9408) (xy 172.2882 -8.4328)
				)
			)
		)
		(zone
			(layer "F.Cu")
			(hatch none 0.5)
			(connect_pads
				(clearance 0)
			)
			(min_thickness 0.25)
			(keepout
				(tracks not_allowed)
				(vias allowed)
				(pads allowed)
				(copperpour not_allowed)
				(footprints allowed)
			)
			(placement
				(enabled no)
				(sheetname "")
			)
			(fill
				(thermal_gap 0.5)
				(thermal_bridge_width 0.5)
				(island_removal_mode 0)
			)
			(polygon
				(pts
					(xy 172.2882 -8.4328) (xy 172.2882 -8.9408) (xy 171.9072 -8.9408) (xy 171.9072 -8.4328)
				)
			)
		)
	)
	(footprint ""
		(layer "F.Cu")
		(at 414.410652 -135.636)
		(property "Reference" "R8A14"
			(at 0 0 0)
			(layer "F.SilkS")
			(hide yes)
			(effects
				(font
					(size 1.27 1.27)
				)
			)
		)
		(property "Value" ""
			(at 0 0 0)
			(layer "F.Fab")
			(effects
				(font
					(size 1.27 1.27)
				)
			)
		)
		(duplicate_pad_numbers_are_jumpers no)
		(fp_poly
			(pts
				(xy -0.2794 -0.1016) (xy 0.2794 -0.1016) (xy 0.2794 0.9906) (xy -0.2794 0.9906)
			)
			(stroke
				(width 0)
				(type default)
			)
			(fill no)
			(layer "F.CrtYd")
		)
		(fp_line
			(start -0.2794 -0.1016)
			(end -0.2794 0.9906)
			(stroke
				(width 0.1)
				(type default)
			)
			(layer "F.Fab")
		)
		(fp_line
			(start -0.2794 0.9906)
			(end 0.2794 0.9906)
			(stroke
				(width 0.1)
				(type default)
			)
			(layer "F.Fab")
		)
		(fp_line
			(start 0.2794 -0.1016)
			(end -0.2794 -0.1016)
			(stroke
				(width 0.1)
				(type default)
			)
			(layer "F.Fab")
		)
		(fp_line
			(start 0.2794 0.9906)
			(end 0.2794 -0.1016)
			(stroke
				(width 0.1)
				(type default)
			)
			(layer "F.Fab")
		)
		(pad "1" smd rect
			(at 0 0)
			(size 0.508 0.508)
			(layers "F.Cu" "F.Mask" "F.Paste")
			(net "P1V05_PCH_STBY")
		)
		(pad "2" smd rect
			(at 0 0.889)
			(size 0.508 0.508)
			(layers "F.Cu" "F.Mask" "F.Paste")
			(net "XDP_TMS")
		)
		(zone
			(layer "F.Cu")
			(hatch none 0.5)
			(connect_pads
				(clearance 0)
			)
			(min_thickness 0.25)
			(keepout
				(tracks allowed)
				(vias not_allowed)
				(pads allowed)
				(copperpour not_allowed)
				(footprints allowed)
			)
			(placement
				(enabled no)
				(sheetname "")
			)
			(fill
				(thermal_gap 0.5)
				(thermal_bridge_width 0.5)
				(island_removal_mode 0)
			)
			(polygon
				(pts
					(xy 414.156652 -135.382) (xy 414.664652 -135.382) (xy 414.664652 -135.001) (xy 414.156652 -135.001)
				)
			)
		)
		(zone
			(layer "F.Cu")
			(hatch none 0.5)
			(connect_pads
				(clearance 0)
			)
			(min_thickness 0.25)
			(keepout
				(tracks not_allowed)
				(vias allowed)
				(pads allowed)
				(copperpour not_allowed)
				(footprints allowed)
			)
			(placement
				(enabled no)
				(sheetname "")
			)
			(fill
				(thermal_gap 0.5)
				(thermal_bridge_width 0.5)
				(island_removal_mode 0)
			)
			(polygon
				(pts
					(xy 414.156652 -135.001) (xy 414.664652 -135.001) (xy 414.664652 -135.382) (xy 414.156652 -135.382)
				)
			)
		)
	)
)
